(kicad_pcb
	(version 20260206)
	(generator "pcbnew")
	(generator_version "10.0")
	(general
		(thickness 1.6)
		(legacy_teardrops no)
	)
	(paper "A4")
	(title_block
		(title "Bryce Canyon_R.DPB_16317-1_OCP.brd")
		(comment 1 "Bryce Canyon / footprints 1217-1223 of 2099")
	)
	(layers
		(0 "F.Cu" signal "TOP")
		(4 "In1.Cu" signal "L2GND")
		(6 "In2.Cu" signal "L3")
		(8 "In3.Cu" signal "L4VCC")
		(10 "In4.Cu" signal "L5VCC")
		(12 "In5.Cu" signal "L6")
		(14 "In6.Cu" signal "L7GND")
		(2 "B.Cu" signal "BOTTOM")
		(9 "F.Adhes" user "F.Adhesive")
		(11 "B.Adhes" user "B.Adhesive")
		(13 "F.Paste" user "Package Geometry/Pastemask Top")
		(15 "B.Paste" user "Package Geometry/Pastemask Bottom")
		(5 "F.SilkS" user "Ref Des/Silkscreen Top")
		(7 "B.SilkS" user "Ref Des/Silkscreen Bottom")
		(1 "F.Mask" user "Board Geometry/Soldermask Top")
		(3 "B.Mask" user "Board Geometry/Soldermask Bottom")
		(17 "Dwgs.User" user "User.Drawings")
		(19 "Cmts.User" user "User.Comments")
		(21 "Eco1.User" user "User.Eco1")
		(23 "Eco2.User" user "User.Eco2")
		(25 "Edge.Cuts" user "Board Geometry/Outline")
		(27 "Margin" user)
		(31 "F.CrtYd" user "Package Geometry/Place Bound Top")
		(29 "B.CrtYd" user "Package Geometry/Place Bound Bottom")
		(35 "F.Fab" user "Ref Des/Assembly Top")
		(33 "B.Fab" user "Ref Des/Assembly Bottom")
	)
	(footprint ""
		(layer "F.Cu")
		(at 364.744 -243.586 180)
		(property "Reference" "R276"
			(at 0 0 180)
			(layer "F.SilkS")
			(hide yes)
			(effects
				(font
					(size 1.27 1.27)
				)
			)
		)
		(property "Value" "1KR2F-3-GP"
			(at 0.064008 -3.993896 180)
			(unlocked yes)
			(layer "F.Fab")
			(hide yes)
			(effects
				(font
					(size 1.016 1.016)
					(thickness 0.1524)
				)
			)
		)
		(property "Device Type" "R402H16"
			(at 0.064008 -5.517896 180)
			(unlocked yes)
			(layer "F.Fab")
			(hide yes)
			(effects
				(font
					(size 1.016 1.016)
					(thickness 0.1524)
				)
			)
		)
		(duplicate_pad_numbers_are_jumpers no)
		(fp_line
			(start 0.508 -0.9398)
			(end -0.508 -0.9398)
			(stroke
				(width 0.1524)
				(type default)
			)
			(layer "F.SilkS")
		)
		(fp_line
			(start -0.508 -0.9398)
			(end -0.508 0.9398)
			(stroke
				(width 0.1524)
				(type default)
			)
			(layer "F.SilkS")
		)
		(fp_rect
			(start -0.508 0.9398)
			(end 0.508 -0.9398)
			(stroke
				(width 0)
				(type default)
			)
			(fill no)
			(layer "F.CrtYd")
		)
		(fp_rect
			(start -0.508 0.9398)
			(end 0.508 -0.9398)
			(stroke
				(width 0)
				(type default)
			)
			(fill no)
			(layer "F.Fab")
		)
		(pad "1" smd custom
			(at 0 -0.4445 180)
			(size 0.1397 0.1397)
			(layers "F.Cu" "F.Mask" "F.Paste")
			(net "P3V3_STBY_B")
			(options
				(clearance outline)
				(anchor circle)
			)
			(primitives
				(gr_poly
					(pts
						(arc
							(start -0.1778 -0.2794)
							(mid -0.249642 -0.249642)
							(end -0.2794 -0.1778)
						)
						(arc
							(start -0.2794 0.1778)
							(mid -0.249642 0.249642)
							(end -0.1778 0.2794)
						)
						(arc
							(start 0.1778 0.2794)
							(mid 0.249642 0.249642)
							(end 0.2794 0.1778)
						)
						(arc
							(start 0.2794 -0.1778)
							(mid 0.249642 -0.249642)
							(end 0.1778 -0.2794)
						)
					)
					(width 0)
					(fill yes)
				)
			)
		)
		(pad "2" smd custom
			(at 0 0.4445 180)
			(size 0.1397 0.1397)
			(layers "F.Cu" "F.Mask" "F.Paste")
			(net "SW_PWR_R_HDD7")
			(options
				(clearance outline)
				(anchor circle)
			)
			(primitives
				(gr_poly
					(pts
						(arc
							(start -0.1778 -0.2794)
							(mid -0.249642 -0.249642)
							(end -0.2794 -0.1778)
						)
						(arc
							(start -0.2794 0.1778)
							(mid -0.249642 0.249642)
							(end -0.1778 0.2794)
						)
						(arc
							(start 0.1778 0.2794)
							(mid 0.249642 0.249642)
							(end 0.2794 0.1778)
						)
						(arc
							(start 0.2794 -0.1778)
							(mid 0.249642 -0.249642)
							(end 0.1778 -0.2794)
						)
					)
					(width 0)
					(fill yes)
				)
			)
		)
	)
	(footprint ""
		(layer "F.Cu")
		(at 378.249942 -180.399944)
		(property "Reference" "LED9"
			(at 0 0 0)
			(layer "F.SilkS")
			(hide yes)
			(effects
				(font
					(size 1.27 1.27)
				)
			)
		)
		(property "Value" "LED-BY-19-GP"
			(at -2.132076 1.414018 0)
			(unlocked yes)
			(layer "F.Fab")
			(hide yes)
			(effects
				(font
					(size 1.016 1.016)
					(thickness 0.1524)
				)
			)
		)
		(property "Device Type" "LED-1615-4PH26"
			(at -2.132076 -0.109982 0)
			(unlocked yes)
			(layer "F.Fab")
			(hide yes)
			(effects
				(font
					(size 1.016 1.016)
					(thickness 0.1524)
				)
			)
		)
		(duplicate_pad_numbers_are_jumpers no)
		(fp_line
			(start -1.2954 0.254)
			(end -1.2954 1.6002)
			(stroke
				(width 0.508)
				(type default)
			)
			(layer "F.SilkS")
		)
		(fp_line
			(start -1.2954 1.6002)
			(end 1.2954 1.6002)
			(stroke
				(width 0.508)
				(type default)
			)
			(layer "F.SilkS")
		)
		(fp_line
			(start -1.1176 -1.4224)
			(end 1.1176 -1.4224)
			(stroke
				(width 0.1524)
				(type default)
			)
			(layer "F.SilkS")
		)
		(fp_line
			(start -1.1176 1.4224)
			(end -1.1176 -1.4224)
			(stroke
				(width 0.1524)
				(type default)
			)
			(layer "F.SilkS")
		)
		(fp_line
			(start 1.1176 -1.4224)
			(end 1.1176 1.4224)
			(stroke
				(width 0.1524)
				(type default)
			)
			(layer "F.SilkS")
		)
		(fp_line
			(start 1.1176 1.4224)
			(end -1.1176 1.4224)
			(stroke
				(width 0.1524)
				(type default)
			)
			(layer "F.SilkS")
		)
		(fp_line
			(start 1.2954 1.6002)
			(end 1.2954 0.254)
			(stroke
				(width 0.508)
				(type default)
			)
			(layer "F.SilkS")
		)
		(fp_rect
			(start -0.7493 0.8001)
			(end 0.7493 -0.8001)
			(stroke
				(width 0)
				(type default)
			)
			(fill no)
			(layer "F.CrtYd")
		)
		(fp_poly
			(pts
				(xy -1.3716 1.6764) (xy -1.3716 -1.6764) (xy 1.3716 -1.6764) (xy 1.3716 0.0635) (xy 0.7493 0.0635)
				(xy 0.7493 -0.8001) (xy -0.7493 -0.8001) (xy -0.7493 0.8001) (xy 0.7493 0.8001) (xy 0.7493 0.0762)
				(xy 1.3716 0.0762) (xy 1.3716 1.6764)
			)
			(stroke
				(width 0)
				(type default)
			)
			(fill no)
			(layer "F.CrtYd")
		)
		(fp_rect
			(start -1.3716 1.6764)
			(end 1.3716 -1.6764)
			(stroke
				(width 0)
				(type default)
			)
			(fill no)
			(layer "F.Fab")
		)
		(pad "1" smd rect
			(at 0.50038 -0.73025)
			(size 0.7112 0.8636)
			(layers "F.Cu" "F.Mask" "F.Paste")
			(net "DRV_ACT_8")
		)
		(pad "2" smd rect
			(at -0.50038 -0.73025)
			(size 0.7112 0.8636)
			(layers "F.Cu" "F.Mask" "F.Paste")
			(net "FLT_HDD8")
		)
		(pad "3" smd rect
			(at 0.50038 0.73025)
			(size 0.7112 0.8636)
			(layers "F.Cu" "F.Mask" "F.Paste")
			(net "DRV_ACT_8_N")
		)
		(pad "4" smd rect
			(at -0.50038 0.73025)
			(size 0.7112 0.8636)
			(layers "F.Cu" "F.Mask" "F.Paste")
			(net "FLT_HDD8_N")
		)
	)
	(footprint ""
		(layer "F.Cu")
		(at 32.463486 -15.219426 90)
		(property "Reference" "C340"
			(at 0 0 90)
			(layer "F.SilkS")
			(hide yes)
			(effects
				(font
					(size 1.27 1.27)
				)
			)
		)
		(property "Value" "SCD01U16V1KX-GP"
			(at -2.8321 -1.7399 90)
			(unlocked yes)
			(layer "F.Fab")
			(hide yes)
			(effects
				(font
					(size 1.016 1.016)
					(thickness 0.1524)
				)
			)
		)
		(property "Device Type" "C0201H13"
			(at -2.8321 -3.2639 90)
			(unlocked yes)
			(layer "F.Fab")
			(hide yes)
			(effects
				(font
					(size 1.016 1.016)
					(thickness 0.1524)
				)
			)
		)
		(duplicate_pad_numbers_are_jumpers no)
		(fp_rect
			(start -0.2794 0.6477)
			(end 0.2794 -0.6477)
			(stroke
				(width 0)
				(type default)
			)
			(fill no)
			(layer "F.CrtYd")
		)
		(fp_rect
			(start -0.2794 0.6477)
			(end 0.2794 -0.6477)
			(stroke
				(width 0)
				(type default)
			)
			(fill no)
			(layer "F.Fab")
		)
		(pad "1" smd custom
			(at 0 -0.2794 90)
			(size 0.0762 0.0762)
			(layers "F.Cu" "F.Mask" "F.Paste")
			(net "SAS_HDD_RX_N24")
			(options
				(clearance outline)
				(anchor circle)
			)
			(primitives
				(gr_poly
					(pts
						(arc
							(start 0.1524 -0.127)
							(mid 0.137521 -0.162921)
							(end 0.1016 -0.1778)
						)
						(arc
							(start -0.1016 -0.1778)
							(mid -0.137521 -0.162921)
							(end -0.1524 -0.127)
						)
						(arc
							(start -0.1524 0.127)
							(mid -0.137521 0.162921)
							(end -0.1016 0.1778)
						)
						(arc
							(start 0.1016 0.1778)
							(mid 0.137521 0.162921)
							(end 0.1524 0.127)
						)
					)
					(width 0)
					(fill yes)
				)
			)
		)
		(pad "2" smd custom
			(at 0 0.2794 90)
			(size 0.0762 0.0762)
			(layers "F.Cu" "F.Mask" "F.Paste")
			(net "PHY_SCC_B_TO_DRV_B_24_DN")
			(options
				(clearance outline)
				(anchor circle)
			)
			(primitives
				(gr_poly
					(pts
						(arc
							(start 0.1524 -0.127)
							(mid 0.137521 -0.162921)
							(end 0.1016 -0.1778)
						)
						(arc
							(start -0.1016 -0.1778)
							(mid -0.137521 -0.162921)
							(end -0.1524 -0.127)
						)
						(arc
							(start -0.1524 0.127)
							(mid -0.137521 0.162921)
							(end -0.1016 0.1778)
						)
						(arc
							(start 0.1016 0.1778)
							(mid 0.137521 0.162921)
							(end 0.1524 0.127)
						)
					)
					(width 0)
					(fill yes)
				)
			)
		)
	)
	(footprint ""
		(layer "F.Cu")
		(at 479.384614 -15.219426 -90)
		(property "Reference" "C483"
			(at 0 0 270)
			(layer "F.SilkS")
			(hide yes)
			(effects
				(font
					(size 1.27 1.27)
				)
			)
		)
		(property "Value" "SCD01U16V1KX-GP"
			(at -2.8321 -1.7399 270)
			(unlocked yes)
			(layer "F.Fab")
			(hide yes)
			(effects
				(font
					(size 1.016 1.016)
					(thickness 0.1524)
				)
			)
		)
		(property "Device Type" "C0201H13"
			(at -2.8321 -3.2639 270)
			(unlocked yes)
			(layer "F.Fab")
			(hide yes)
			(effects
				(font
					(size 1.016 1.016)
					(thickness 0.1524)
				)
			)
		)
		(duplicate_pad_numbers_are_jumpers no)
		(fp_rect
			(start -0.2794 0.6477)
			(end 0.2794 -0.6477)
			(stroke
				(width 0)
				(type default)
			)
			(fill no)
			(layer "F.CrtYd")
		)
		(fp_rect
			(start -0.2794 0.6477)
			(end 0.2794 -0.6477)
			(stroke
				(width 0)
				(type default)
			)
			(fill no)
			(layer "F.Fab")
		)
		(pad "1" smd custom
			(at 0 -0.2794 270)
			(size 0.0762 0.0762)
			(layers "F.Cu" "F.Mask" "F.Paste")
			(net "SAS_HDD_RX_N35")
			(options
				(clearance outline)
				(anchor circle)
			)
			(primitives
				(gr_poly
					(pts
						(arc
							(start 0.1524 -0.127)
							(mid 0.137521 -0.162921)
							(end 0.1016 -0.1778)
						)
						(arc
							(start -0.1016 -0.1778)
							(mid -0.137521 -0.162921)
							(end -0.1524 -0.127)
						)
						(arc
							(start -0.1524 0.127)
							(mid -0.137521 0.162921)
							(end -0.1016 0.1778)
						)
						(arc
							(start 0.1016 0.1778)
							(mid 0.137521 0.162921)
							(end 0.1524 0.127)
						)
					)
					(width 0)
					(fill yes)
				)
			)
		)
		(pad "2" smd custom
			(at 0 0.2794 270)
			(size 0.0762 0.0762)
			(layers "F.Cu" "F.Mask" "F.Paste")
			(net "PHY_SCC_B_TO_DRV_B_35_DN")
			(options
				(clearance outline)
				(anchor circle)
			)
			(primitives
				(gr_poly
					(pts
						(arc
							(start 0.1524 -0.127)
							(mid 0.137521 -0.162921)
							(end 0.1016 -0.1778)
						)
						(arc
							(start -0.1016 -0.1778)
							(mid -0.137521 -0.162921)
							(end -0.1524 -0.127)
						)
						(arc
							(start -0.1524 0.127)
							(mid -0.137521 0.162921)
							(end -0.1016 0.1778)
						)
						(arc
							(start 0.1016 0.1778)
							(mid 0.137521 0.162921)
							(end 0.1524 0.127)
						)
					)
					(width 0)
					(fill yes)
				)
			)
		)
	)
	(footprint ""
		(layer "F.Cu")
		(at 18.209768 -102.43947 -90)
		(property "Reference" "R338"
			(at 0 0 270)
			(layer "F.SilkS")
			(hide yes)
			(effects
				(font
					(size 1.27 1.27)
				)
			)
		)
		(property "Value" "4K7R2F-GP"
			(at 0.064008 -3.993896 270)
			(unlocked yes)
			(layer "F.Fab")
			(hide yes)
			(effects
				(font
					(size 1.016 1.016)
					(thickness 0.1524)
				)
			)
		)
		(property "Device Type" "R402H16"
			(at 0.064008 -5.517896 270)
			(unlocked yes)
			(layer "F.Fab")
			(hide yes)
			(effects
				(font
					(size 1.016 1.016)
					(thickness 0.1524)
				)
			)
		)
		(duplicate_pad_numbers_are_jumpers no)
		(fp_line
			(start -0.508 -0.9398)
			(end -0.508 0.9398)
			(stroke
				(width 0.1524)
				(type default)
			)
			(layer "F.SilkS")
		)
		(fp_line
			(start 0.508 -0.9398)
			(end -0.508 -0.9398)
			(stroke
				(width 0.1524)
				(type default)
			)
			(layer "F.SilkS")
		)
		(fp_rect
			(start -0.508 0.9398)
			(end 0.508 -0.9398)
			(stroke
				(width 0)
				(type default)
			)
			(fill no)
			(layer "F.CrtYd")
		)
		(fp_rect
			(start -0.508 0.9398)
			(end 0.508 -0.9398)
			(stroke
				(width 0)
				(type default)
			)
			(fill no)
			(layer "F.Fab")
		)
		(pad "1" smd custom
			(at 0 -0.4445 270)
			(size 0.1397 0.1397)
			(layers "F.Cu" "F.Mask" "F.Paste")
			(net "DRIVE_B_12_FLT_LED")
			(options
				(clearance outline)
				(anchor circle)
			)
			(primitives
				(gr_poly
					(pts
						(arc
							(start -0.1778 -0.2794)
							(mid -0.249642 -0.249642)
							(end -0.2794 -0.1778)
						)
						(arc
							(start -0.2794 0.1778)
							(mid -0.249642 0.249642)
							(end -0.1778 0.2794)
						)
						(arc
							(start 0.1778 0.2794)
							(mid 0.249642 0.249642)
							(end 0.2794 0.1778)
						)
						(arc
							(start 0.2794 -0.1778)
							(mid 0.249642 -0.249642)
							(end 0.1778 -0.2794)
						)
					)
					(width 0)
					(fill yes)
				)
			)
		)
		(pad "2" smd custom
			(at 0 0.4445 270)
			(size 0.1397 0.1397)
			(layers "F.Cu" "F.Mask" "F.Paste")
			(net "GND")
			(options
				(clearance outline)
				(anchor circle)
			)
			(primitives
				(gr_poly
					(pts
						(arc
							(start -0.1778 -0.2794)
							(mid -0.249642 -0.249642)
							(end -0.2794 -0.1778)
						)
						(arc
							(start -0.2794 0.1778)
							(mid -0.249642 0.249642)
							(end -0.1778 0.2794)
						)
						(arc
							(start 0.1778 0.2794)
							(mid 0.249642 0.249642)
							(end 0.2794 0.1778)
						)
						(arc
							(start 0.2794 -0.1778)
							(mid 0.249642 -0.249642)
							(end 0.1778 -0.2794)
						)
					)
					(width 0)
					(fill yes)
				)
			)
		)
	)
	(footprint ""
		(layer "F.Cu")
		(at 329.819 -267.843 180)
		(property "Reference" "C108"
			(at 0 0 180)
			(layer "F.SilkS")
			(hide yes)
			(effects
				(font
					(size 1.27 1.27)
				)
			)
		)
		(property "Value" "SC1U16V3KX-5GP"
			(at 0 -2.8194 180)
			(unlocked yes)
			(layer "F.Fab")
			(hide yes)
			(effects
				(font
					(size 1.016 1.016)
					(thickness 0.1524)
				)
			)
		)
		(property "Device Type" "C603H36"
			(at 0 -4.3434 180)
			(unlocked yes)
			(layer "F.Fab")
			(hide yes)
			(effects
				(font
					(size 1.016 1.016)
					(thickness 0.1524)
				)
			)
		)
		(duplicate_pad_numbers_are_jumpers no)
		(fp_line
			(start 0.508 0)
			(end -0.508 0)
			(stroke
				(width 0.2032)
				(type default)
			)
			(layer "F.SilkS")
		)
		(fp_rect
			(start -0.5842 1.3335)
			(end 0.5842 -1.3335)
			(stroke
				(width 0)
				(type default)
			)
			(fill no)
			(layer "F.CrtYd")
		)
		(fp_rect
			(start -0.5842 1.3335)
			(end 0.5842 -1.3335)
			(stroke
				(width 0)
				(type default)
			)
			(fill no)
			(layer "F.Fab")
		)
		(pad "1" smd custom
			(at 0 -0.762 180)
			(size 0.2159 0.2159)
			(layers "F.Cu" "F.Mask" "F.Paste")
			(net "P5V_HDD6")
			(options
				(clearance outline)
				(anchor circle)
			)
			(primitives
				(gr_poly
					(pts
						(arc
							(start -0.3302 -0.4318)
							(mid -0.402042 -0.402042)
							(end -0.4318 -0.3302)
						)
						(arc
							(start -0.4318 0.3302)
							(mid -0.402042 0.402042)
							(end -0.3302 0.4318)
						)
						(arc
							(start 0.3302 0.4318)
							(mid 0.402042 0.402042)
							(end 0.4318 0.3302)
						)
						(arc
							(start 0.4318 -0.3302)
							(mid 0.402042 -0.402042)
							(end 0.3302 -0.4318)
						)
					)
					(width 0)
					(fill yes)
				)
			)
		)
		(pad "2" smd custom
			(at 0 0.762 180)
			(size 0.2159 0.2159)
			(layers "F.Cu" "F.Mask" "F.Paste")
			(net "GND")
			(options
				(clearance outline)
				(anchor circle)
			)
			(primitives
				(gr_poly
					(pts
						(arc
							(start -0.3302 -0.4318)
							(mid -0.402042 -0.402042)
							(end -0.4318 -0.3302)
						)
						(arc
							(start -0.4318 0.3302)
							(mid -0.402042 0.402042)
							(end -0.3302 0.4318)
						)
						(arc
							(start 0.3302 0.4318)
							(mid 0.402042 0.402042)
							(end 0.4318 0.3302)
						)
						(arc
							(start 0.4318 -0.3302)
							(mid 0.402042 -0.402042)
							(end 0.3302 -0.4318)
						)
					)
					(width 0)
					(fill yes)
				)
			)
		)
	)
	(footprint ""
		(layer "F.Cu")
		(at 395.224 -131.318 -90)
		(property "Reference" "Q95"
			(at 0 0 270)
			(layer "F.SilkS")
			(hide yes)
			(effects
				(font
					(size 1.27 1.27)
				)
			)
		)
		(property "Value" "2N7002KDW-GP"
			(at -2.3622 -8.2042 270)
			(unlocked yes)
			(layer "F.Fab")
			(hide yes)
			(effects
				(font
					(size 1.016 1.016)
					(thickness 0.1524)
				)
			)
		)
		(property "Device Type" "SOT-363H44"
			(at -2.3622 -10.1092 270)
			(unlocked yes)
			(layer "F.Fab")
			(hide yes)
			(effects
				(font
					(size 1.016 1.016)
					(thickness 0.1524)
				)
			)
		)
		(duplicate_pad_numbers_are_jumpers no)
		(fp_line
			(start -1.4478 1.7018)
			(end 1.4478 1.7018)
			(stroke
				(width 0.1524)
				(type default)
			)
			(layer "F.SilkS")
		)
		(fp_line
			(start 1.4478 1.7018)
			(end 1.4478 -1.7018)
			(stroke
				(width 0.1524)
				(type default)
			)
			(layer "F.SilkS")
		)
		(fp_line
			(start -1.27 1.524)
			(end -1.27 0.6604)
			(stroke
				(width 0.4826)
				(type default)
			)
			(layer "F.SilkS")
		)
		(fp_line
			(start -1.4478 -1.7018)
			(end -1.4478 1.7018)
			(stroke
				(width 0.1524)
				(type default)
			)
			(layer "F.SilkS")
		)
		(fp_line
			(start 1.4478 -1.7018)
			(end -1.4478 -1.7018)
			(stroke
				(width 0.1524)
				(type default)
			)
			(layer "F.SilkS")
		)
		(fp_poly
			(pts
				(xy -1.524 -1.778) (xy 1.524 -1.778) (xy 1.524 1.778) (xy -1.524 1.778)
			)
			(stroke
				(width 0)
				(type default)
			)
			(fill no)
			(layer "F.CrtYd")
		)
		(fp_poly
			(pts
				(xy -1.524 -1.778) (xy 1.524 -1.778) (xy 1.524 1.778) (xy -1.524 1.778)
			)
			(stroke
				(width 0)
				(type default)
			)
			(fill no)
			(layer "F.Fab")
		)
		(pad "1" smd rect
			(at -0.65024 0.9398 270)
			(size 0.4064 1.016)
			(layers "F.Cu" "F.Mask" "F.Paste")
			(net "GND")
		)
		(pad "2" smd rect
			(at 0 0.9398 270)
			(size 0.4064 1.016)
			(layers "F.Cu" "F.Mask" "F.Paste")
			(net "SW_PWR_R_HDD20")
		)
		(pad "3" smd rect
			(at 0.65024 0.9398 270)
			(size 0.4064 1.016)
			(layers "F.Cu" "F.Mask" "F.Paste")
			(net "SW_HDD_P20")
		)
		(pad "4" smd rect
			(at 0.65024 -0.9398 270)
			(size 0.4064 1.016)
			(layers "F.Cu" "F.Mask" "F.Paste")
			(net "GND")
		)
		(pad "5" smd rect
			(at 0 -0.9398 270)
			(size 0.4064 1.016)
			(layers "F.Cu" "F.Mask" "F.Paste")
			(net "SW_HDD_G20")
		)
		(pad "6" smd rect
			(at -0.65024 -0.9398 270)
			(size 0.4064 1.016)
			(layers "F.Cu" "F.Mask" "F.Paste")
			(net "SW_HDD_R20")
		)
	)
)
